# T6G (Grand Teton) — schematic netlist excerpt (pin names and nets, part order shuffled) for the footprints in the layout excerpt that follows; sources: Cadence DE-HDL packaged netlist, KiCad conversion of 04192023_DAF0TMB3IC0_F0TG_MB_C_brd_V02_OCP.brd

R6138  Q_RES  1K 1% EMPTY  pkg 0402LF  page 84 : A = P3V3_AUX ; B = FM_BOARD_BMC_SKU_ID2
R3134  Q_RES  1K 1% CHIP  pkg 0402LF  page 140 : A = P3V3_AUX ; B = OCP_V3_2_PRSNT2_R_N

(kicad_pcb
	(version 20260206)
	(generator "pcbnew")
	(generator_version "10.0")
	(general
		(thickness 1.6)
		(legacy_teardrops no)
	)
	(paper "A4")
	(title_block
		(title "04192023_DAF0TMB3IC0_F0TG_MB_C_brd_V02_OCP.brd")
		(comment 1 "Grand Teton / footprints 4291-4292 of 8354")
	)
	(layers
		(0 "F.Cu" signal "TOP")
		(4 "In1.Cu" signal "GND")
		(6 "In2.Cu" signal "IN1")
		(8 "In3.Cu" signal "GND1")
		(10 "In4.Cu" signal "IN2")
		(12 "In5.Cu" signal "GND2")
		(14 "In6.Cu" signal "IN3")
		(16 "In7.Cu" signal "GND3")
		(18 "In8.Cu" signal "VCC")
		(20 "In9.Cu" signal "VCC1")
		(22 "In10.Cu" signal "GND4")
		(24 "In11.Cu" signal "IN4")
		(26 "In12.Cu" signal "GND5")
		(28 "In13.Cu" signal "IN5")
		(30 "In14.Cu" signal "GND6")
		(32 "In15.Cu" signal "IN6")
		(34 "In16.Cu" signal "GND7")
		(2 "B.Cu" signal "BOTTOM")
		(9 "F.Adhes" user "F.Adhesive")
		(11 "B.Adhes" user "B.Adhesive")
		(13 "F.Paste" user "Package Geometry/Pastemask Top")
		(15 "B.Paste" user "Package Geometry/Pastemask Bottom")
		(5 "F.SilkS" user "Ref Des/Silkscreen Top")
		(7 "B.SilkS" user "Ref Des/Silkscreen Bottom")
		(1 "F.Mask" user "Board Geometry/Soldermask Top")
		(3 "B.Mask" user "Board Geometry/Soldermask Bottom")
		(17 "Dwgs.User" user "User.Drawings")
		(19 "Cmts.User" user "User.Comments")
		(21 "Eco1.User" user "User.Eco1")
		(23 "Eco2.User" user "User.Eco2")
		(25 "Edge.Cuts" user "Board Geometry/Outline")
		(27 "Margin" user)
		(31 "F.CrtYd" user "Package Geometry/Place Bound Top")
		(29 "B.CrtYd" user "Package Geometry/Place Bound Bottom")
		(35 "F.Fab" user "Ref Des/Assembly Top")
		(33 "B.Fab" user "Ref Des/Assembly Bottom")
	)
	(footprint ""
		(layer "F.Cu")
		(at 168.39057 -123.683014)
		(property "Reference" "R6138"
			(at 0 0 0)
			(layer "F.SilkS")
			(hide yes)
			(effects
				(font
					(size 1.27 1.27)
				)
			)
		)
		(property "Value" ""
			(at 0 0 0)
			(layer "F.Fab")
			(effects
				(font
					(size 1.27 1.27)
				)
			)
		)
		(duplicate_pad_numbers_are_jumpers no)
		(fp_line
			(start -0.7874 -0.4064)
			(end 0.7874 -0.4064)
			(stroke
				(width 0.1524)
				(type default)
			)
			(layer "F.SilkS")
		)
		(fp_line
			(start -0.7874 0.4064)
			(end -0.7874 -0.4064)
			(stroke
				(width 0.1524)
				(type default)
			)
			(layer "F.SilkS")
		)
		(fp_line
			(start 0.7874 -0.4064)
			(end 0.7874 0.4064)
			(stroke
				(width 0.1524)
				(type default)
			)
			(layer "F.SilkS")
		)
		(fp_line
			(start 0.7874 0.4064)
			(end -0.7874 0.4064)
			(stroke
				(width 0.1524)
				(type default)
			)
			(layer "F.SilkS")
		)
		(fp_line
			(start -0.67945 -0.305054)
			(end -0.12065 -0.305054)
			(stroke
				(width 0.1)
				(type default)
			)
			(layer "F.Fab")
		)
		(fp_line
			(start -0.67945 0.3048)
			(end -0.67945 -0.305054)
			(stroke
				(width 0.1)
				(type default)
			)
			(layer "F.Fab")
		)
		(fp_line
			(start -0.12065 -0.305054)
			(end -0.12065 -0.2794)
			(stroke
				(width 0.1)
				(type default)
			)
			(layer "F.Fab")
		)
		(fp_line
			(start -0.12065 -0.2794)
			(end 0.12065 -0.2794)
			(stroke
				(width 0.1)
				(type default)
			)
			(layer "F.Fab")
		)
		(fp_line
			(start -0.12065 0.2794)
			(end -0.12065 0.3048)
			(stroke
				(width 0.1)
				(type default)
			)
			(layer "F.Fab")
		)
		(fp_line
			(start -0.12065 0.3048)
			(end -0.67945 0.3048)
			(stroke
				(width 0.1)
				(type default)
			)
			(layer "F.Fab")
		)
		(fp_line
			(start 0.120396 0.2794)
			(end -0.12065 0.2794)
			(stroke
				(width 0.1)
				(type default)
			)
			(layer "F.Fab")
		)
		(fp_line
			(start 0.120396 0.3048)
			(end 0.120396 0.2794)
			(stroke
				(width 0.1)
				(type default)
			)
			(layer "F.Fab")
		)
		(fp_line
			(start 0.12065 -0.3048)
			(end 0.67945 -0.3048)
			(stroke
				(width 0.1)
				(type default)
			)
			(layer "F.Fab")
		)
		(fp_line
			(start 0.12065 -0.2794)
			(end 0.12065 -0.3048)
			(stroke
				(width 0.1)
				(type default)
			)
			(layer "F.Fab")
		)
		(fp_line
			(start 0.67945 -0.3048)
			(end 0.67945 0.3048)
			(stroke
				(width 0.1)
				(type default)
			)
			(layer "F.Fab")
		)
		(fp_line
			(start 0.67945 0.3048)
			(end 0.120396 0.3048)
			(stroke
				(width 0.1)
				(type default)
			)
			(layer "F.Fab")
		)
		(pad "1" smd circle
			(at -0.40005 0)
			(size 0 0)
			(layers "F.Cu" "F.Mask" "F.Paste")
			(net "P3V3_AUX")
		)
		(pad "2" smd circle
			(at 0.40005 0)
			(size 0 0)
			(layers "F.Cu" "F.Mask" "F.Paste")
			(net "FM_BOARD_BMC_SKU_ID2")
		)
	)
	(footprint ""
		(layer "F.Cu")
		(at 9.74471 -71.860664)
		(property "Reference" "R3134"
			(at 0 0 0)
			(layer "F.SilkS")
			(hide yes)
			(effects
				(font
					(size 1.27 1.27)
				)
			)
		)
		(property "Value" ""
			(at 0 0 0)
			(layer "F.Fab")
			(effects
				(font
					(size 1.27 1.27)
				)
			)
		)
		(duplicate_pad_numbers_are_jumpers no)
		(fp_line
			(start -0.7874 -0.4064)
			(end 0.7874 -0.4064)
			(stroke
				(width 0.1524)
				(type default)
			)
			(layer "F.SilkS")
		)
		(fp_line
			(start -0.7874 0.4064)
			(end -0.7874 -0.4064)
			(stroke
				(width 0.1524)
				(type default)
			)
			(layer "F.SilkS")
		)
		(fp_line
			(start 0.7874 -0.4064)
			(end 0.7874 0.4064)
			(stroke
				(width 0.1524)
				(type default)
			)
			(layer "F.SilkS")
		)
		(fp_line
			(start 0.7874 0.4064)
			(end -0.7874 0.4064)
			(stroke
				(width 0.1524)
				(type default)
			)
			(layer "F.SilkS")
		)
		(fp_line
			(start -0.67945 -0.305054)
			(end -0.12065 -0.305054)
			(stroke
				(width 0.1)
				(type default)
			)
			(layer "F.Fab")
		)
		(fp_line
			(start -0.67945 0.3048)
			(end -0.67945 -0.305054)
			(stroke
				(width 0.1)
				(type default)
			)
			(layer "F.Fab")
		)
		(fp_line
			(start -0.12065 -0.305054)
			(end -0.12065 -0.2794)
			(stroke
				(width 0.1)
				(type default)
			)
			(layer "F.Fab")
		)
		(fp_line
			(start -0.12065 -0.2794)
			(end 0.12065 -0.2794)
			(stroke
				(width 0.1)
				(type default)
			)
			(layer "F.Fab")
		)
		(fp_line
			(start -0.12065 0.2794)
			(end -0.12065 0.3048)
			(stroke
				(width 0.1)
				(type default)
			)
			(layer "F.Fab")
		)
		(fp_line
			(start -0.12065 0.3048)
			(end -0.67945 0.3048)
			(stroke
				(width 0.1)
				(type default)
			)
			(layer "F.Fab")
		)
		(fp_line
			(start 0.120396 0.2794)
			(end -0.12065 0.2794)
			(stroke
				(width 0.1)
				(type default)
			)
			(layer "F.Fab")
		)
		(fp_line
			(start 0.120396 0.3048)
			(end 0.120396 0.2794)
			(stroke
				(width 0.1)
				(type default)
			)
			(layer "F.Fab")
		)
		(fp_line
			(start 0.12065 -0.3048)
			(end 0.67945 -0.3048)
			(stroke
				(width 0.1)
				(type default)
			)
			(layer "F.Fab")
		)
		(fp_line
			(start 0.12065 -0.2794)
			(end 0.12065 -0.3048)
			(stroke
				(width 0.1)
				(type default)
			)
			(layer "F.Fab")
		)
		(fp_line
			(start 0.67945 -0.3048)
			(end 0.67945 0.3048)
			(stroke
				(width 0.1)
				(type default)
			)
			(layer "F.Fab")
		)
		(fp_line
			(start 0.67945 0.3048)
			(end 0.120396 0.3048)
			(stroke
				(width 0.1)
				(type default)
			)
			(layer "F.Fab")
		)
		(pad "1" smd circle
			(at -0.40005 0)
			(size 0 0)
			(layers "F.Cu" "F.Mask" "F.Paste")
			(net "P3V3_AUX")
		)
		(pad "2" smd circle
			(at 0.40005 0)
			(size 0 0)
			(layers "F.Cu" "F.Mask" "F.Paste")
			(net "OCP_V3_2_PRSNT2_R_N")
		)
	)
)
